# BASEBOARD_FAB2 (Tioga Pass) — schematic netlist excerpt (pin names and nets, part order shuffled) for the footprints in the layout excerpt that follows; sources: Cadence DE-HDL packaged netlist, KiCad conversion of Wiwynn_Tioga_Pass_MB.brd

C3P5  CAP_A  0.1UF 16V 10% X7R  pkg 0402V  page 211 : A = VR_PVCCIO_CPU0_VD12 ; B = GND
R9P28  RES  100.0K 1% CHIP  pkg 0402  page 199 : A = P12V_PSU ; B = A_HSC_OV
C9U2  CAPP  470UF 2.5V 20% ALUM  pkg 3018  page 225 : A = PVDDQ_GHJ ; B = GND

(kicad_pcb
	(version 20260206)
	(generator "pcbnew")
	(generator_version "10.0")
	(general
		(thickness 1.6)
		(legacy_teardrops no)
	)
	(paper "A4")
	(title_block
		(title "Wiwynn_Tioga_Pass_MB.brd")
		(comment 1 "Tioga Pass / footprints 3099-3101 of 4770")
	)
	(layers
		(0 "F.Cu" signal "TOP")
		(4 "In1.Cu" signal "L2GND")
		(6 "In2.Cu" signal "L3")
		(8 "In3.Cu" signal "L4GND")
		(10 "In4.Cu" signal "L5")
		(12 "In5.Cu" signal "L6GND")
		(14 "In6.Cu" signal "L7VCC")
		(16 "In7.Cu" signal "L8VCC")
		(18 "In8.Cu" signal "L9GND")
		(20 "In9.Cu" signal "L10")
		(22 "In10.Cu" signal "L11GND")
		(24 "In11.Cu" signal "L12")
		(26 "In12.Cu" signal "L13GND")
		(2 "B.Cu" signal "BOTTOM")
		(9 "F.Adhes" user "F.Adhesive")
		(11 "B.Adhes" user "B.Adhesive")
		(13 "F.Paste" user "Package Geometry/Pastemask Top")
		(15 "B.Paste" user "Package Geometry/Pastemask Bottom")
		(5 "F.SilkS" user "Ref Des/Silkscreen Top")
		(7 "B.SilkS" user "Ref Des/Silkscreen Bottom")
		(1 "F.Mask" user "Board Geometry/Soldermask Top")
		(3 "B.Mask" user "Board Geometry/Soldermask Bottom")
		(17 "Dwgs.User" user "User.Drawings")
		(19 "Cmts.User" user "User.Comments")
		(21 "Eco1.User" user "User.Eco1")
		(23 "Eco2.User" user "User.Eco2")
		(25 "Edge.Cuts" user "Board Geometry/Outline")
		(27 "Margin" user)
		(31 "F.CrtYd" user "Package Geometry/Place Bound Top")
		(29 "B.CrtYd" user "Package Geometry/Place Bound Bottom")
		(35 "F.Fab" user "Ref Des/Assembly Top")
		(33 "B.Fab" user "Ref Des/Assembly Bottom")
	)
	(footprint ""
		(layer "B.Cu")
		(at 17.9832 -14.3002 -90)
		(property "Reference" "C9U2"
			(at -1.87833 9.144 0)
			(unlocked yes)
			(layer "B.SilkS")
			(effects
				(font
					(size 0.7874 0.5842)
					(thickness 0.1524)
				)
				(justify mirror)
			)
		)
		(property "Value" ""
			(at 0 0 90)
			(layer "B.Fab")
			(effects
				(font
					(size 1.27 1.27)
				)
				(justify mirror)
			)
		)
		(duplicate_pad_numbers_are_jumpers no)
		(fp_line
			(start -2.286 7.366)
			(end -1.600708 7.366)
			(stroke
				(width 0.1524)
				(type default)
			)
			(layer "B.SilkS")
		)
		(fp_line
			(start -2.286 7.366)
			(end -2.286 1.63195)
			(stroke
				(width 0.1524)
				(type default)
			)
			(layer "B.SilkS")
		)
		(fp_line
			(start 2.286 7.366)
			(end 1.60147 7.366)
			(stroke
				(width 0.1524)
				(type default)
			)
			(layer "B.SilkS")
		)
		(fp_line
			(start 2.286 7.366)
			(end 2.286 1.632712)
			(stroke
				(width 0.1524)
				(type default)
			)
			(layer "B.SilkS")
		)
		(fp_line
			(start -2.504948 1.633728)
			(end -1.6002 1.633728)
			(stroke
				(width 0.1524)
				(type default)
			)
			(layer "B.SilkS")
		)
		(fp_line
			(start 2.563114 1.633728)
			(end 1.6002 1.633728)
			(stroke
				(width 0.1524)
				(type default)
			)
			(layer "B.SilkS")
		)
		(fp_line
			(start -2.504948 -1.616456)
			(end -2.504948 1.633728)
			(stroke
				(width 0.1524)
				(type default)
			)
			(layer "B.SilkS")
		)
		(fp_line
			(start -1.6002 -1.616456)
			(end -2.504948 -1.616456)
			(stroke
				(width 0.1524)
				(type default)
			)
			(layer "B.SilkS")
		)
		(fp_line
			(start 1.6002 -1.616456)
			(end 2.563114 -1.616456)
			(stroke
				(width 0.1524)
				(type default)
			)
			(layer "B.SilkS")
		)
		(fp_line
			(start 2.563114 -1.616456)
			(end 2.563114 1.633728)
			(stroke
				(width 0.1524)
				(type default)
			)
			(layer "B.SilkS")
		)
		(fp_rect
			(start 2.286 -0.254)
			(end -2.286 7.366)
			(stroke
				(width 0)
				(type default)
			)
			(fill no)
			(layer "B.CrtYd")
		)
		(fp_line
			(start -2.286 7.366)
			(end 2.286 7.366)
			(stroke
				(width 0.1)
				(type default)
			)
			(layer "B.Fab")
		)
		(fp_line
			(start 2.286 7.366)
			(end 2.286 -0.254)
			(stroke
				(width 0.1)
				(type default)
			)
			(layer "B.Fab")
		)
		(fp_line
			(start -2.286 -0.254)
			(end -2.286 7.366)
			(stroke
				(width 0.1)
				(type default)
			)
			(layer "B.Fab")
		)
		(fp_line
			(start 2.286 -0.254)
			(end -2.286 -0.254)
			(stroke
				(width 0.1)
				(type default)
			)
			(layer "B.Fab")
		)
		(pad "1" smd rect
			(at 0 0 90)
			(size 2.54 3.048)
			(layers "B.Cu" "B.Mask" "B.Paste")
			(net "PVDDQ_GHJ")
		)
		(pad "2" smd rect
			(at 0 7.112 90)
			(size 2.54 3.048)
			(layers "B.Cu" "B.Mask" "B.Paste")
			(net "GND")
		)
	)
	(footprint ""
		(layer "B.Cu")
		(at 21.717 -69.85 180)
		(property "Reference" "R9P28"
			(at 0 0 0)
			(layer "B.SilkS")
			(hide yes)
			(effects
				(font
					(size 1.27 1.27)
				)
				(justify mirror)
			)
		)
		(property "Value" ""
			(at 0 0 0)
			(layer "B.Fab")
			(effects
				(font
					(size 1.27 1.27)
				)
				(justify mirror)
			)
		)
		(duplicate_pad_numbers_are_jumpers no)
		(fp_poly
			(pts
				(xy 0.2794 -0.1016) (xy -0.2794 -0.1016) (xy -0.2794 0.9906) (xy 0.2794 0.9906)
			)
			(stroke
				(width 0)
				(type default)
			)
			(fill no)
			(layer "B.CrtYd")
		)
		(fp_line
			(start 0.2794 0.9906)
			(end -0.2794 0.9906)
			(stroke
				(width 0.1)
				(type default)
			)
			(layer "B.Fab")
		)
		(fp_line
			(start 0.2794 -0.1016)
			(end 0.2794 0.9906)
			(stroke
				(width 0.1)
				(type default)
			)
			(layer "B.Fab")
		)
		(fp_line
			(start -0.2794 0.9906)
			(end -0.2794 -0.1016)
			(stroke
				(width 0.1)
				(type default)
			)
			(layer "B.Fab")
		)
		(fp_line
			(start -0.2794 -0.1016)
			(end 0.2794 -0.1016)
			(stroke
				(width 0.1)
				(type default)
			)
			(layer "B.Fab")
		)
		(pad "1" smd rect
			(at 0 0)
			(size 0.508 0.508)
			(layers "B.Cu" "B.Mask" "B.Paste")
			(net "P12V_PSU")
		)
		(pad "2" smd rect
			(at 0 0.889)
			(size 0.508 0.508)
			(layers "B.Cu" "B.Mask" "B.Paste")
			(net "A_HSC_OV")
		)
		(zone
			(layer "B.Cu")
			(hatch none 0.5)
			(connect_pads
				(clearance 0)
			)
			(min_thickness 0.25)
			(keepout
				(tracks not_allowed)
				(vias allowed)
				(pads allowed)
				(copperpour not_allowed)
				(footprints allowed)
			)
			(placement
				(enabled no)
				(sheetname "")
			)
			(fill
				(thermal_gap 0.5)
				(thermal_bridge_width 0.5)
				(island_removal_mode 0)
			)
			(polygon
				(pts
					(xy 21.463 -70.485) (xy 21.971 -70.485) (xy 21.971 -70.104) (xy 21.463 -70.104)
				)
			)
		)
		(zone
			(layer "B.Cu")
			(hatch none 0.5)
			(connect_pads
				(clearance 0)
			)
			(min_thickness 0.25)
			(keepout
				(tracks allowed)
				(vias not_allowed)
				(pads allowed)
				(copperpour not_allowed)
				(footprints allowed)
			)
			(placement
				(enabled no)
				(sheetname "")
			)
			(fill
				(thermal_gap 0.5)
				(thermal_bridge_width 0.5)
				(island_removal_mode 0)
			)
			(polygon
				(pts
					(xy 21.463 -70.104) (xy 21.971 -70.104) (xy 21.971 -70.485) (xy 21.463 -70.485)
				)
			)
		)
	)
	(footprint ""
		(layer "B.Cu")
		(at 349.123 -83.5406)
		(property "Reference" "C3P5"
			(at 0 0 0)
			(layer "B.SilkS")
			(hide yes)
			(effects
				(font
					(size 1.27 1.27)
				)
				(justify mirror)
			)
		)
		(property "Value" ""
			(at 0 0 0)
			(layer "B.Fab")
			(effects
				(font
					(size 1.27 1.27)
				)
				(justify mirror)
			)
		)
		(duplicate_pad_numbers_are_jumpers no)
		(fp_poly
			(pts
				(xy -0.3048 -0.1016) (xy -0.3048 0.9906) (xy 0.3048 0.9906) (xy 0.3048 -0.1016)
			)
			(stroke
				(width 0)
				(type default)
			)
			(fill no)
			(layer "B.CrtYd")
		)
		(fp_line
			(start -0.3048 -0.1016)
			(end 0.3048 -0.1016)
			(stroke
				(width 0.1)
				(type default)
			)
			(layer "B.Fab")
		)
		(fp_line
			(start -0.3048 0.9906)
			(end -0.3048 -0.1016)
			(stroke
				(width 0.1)
				(type default)
			)
			(layer "B.Fab")
		)
		(fp_line
			(start 0.3048 -0.1016)
			(end 0.3048 0.9906)
			(stroke
				(width 0.1)
				(type default)
			)
			(layer "B.Fab")
		)
		(fp_line
			(start 0.3048 0.9906)
			(end -0.3048 0.9906)
			(stroke
				(width 0.1)
				(type default)
			)
			(layer "B.Fab")
		)
		(pad "1" smd rect
			(at 0 0 180)
			(size 0.508 0.508)
			(layers "B.Cu" "B.Mask" "B.Paste")
			(net "VR_PVCCIO_CPU0_VD12")
		)
		(pad "2" smd rect
			(at 0 0.889 180)
			(size 0.508 0.508)
			(layers "B.Cu" "B.Mask" "B.Paste")
			(net "GND")
		)
		(zone
			(layer "B.Cu")
			(hatch none 0.5)
			(connect_pads
				(clearance 0)
			)
			(min_thickness 0.25)
			(keepout
				(tracks allowed)
				(vias not_allowed)
				(pads allowed)
				(copperpour not_allowed)
				(footprints allowed)
			)
			(placement
				(enabled no)
				(sheetname "")
			)
			(fill
				(thermal_gap 0.5)
				(thermal_bridge_width 0.5)
				(island_removal_mode 0)
			)
			(polygon
				(pts
					(xy 349.377 -83.2866) (xy 348.869 -83.2866) (xy 348.869 -82.9056) (xy 349.377 -82.9056)
				)
			)
		)
		(zone
			(layer "B.Cu")
			(hatch none 0.5)
			(connect_pads
				(clearance 0)
			)
			(min_thickness 0.25)
			(keepout
				(tracks not_allowed)
				(vias allowed)
				(pads allowed)
				(copperpour not_allowed)
				(footprints allowed)
			)
			(placement
				(enabled no)
				(sheetname "")
			)
			(fill
				(thermal_gap 0.5)
				(thermal_bridge_width 0.5)
				(island_removal_mode 0)
			)
			(polygon
				(pts
					(xy 349.377 -82.9056) (xy 348.869 -82.9056) (xy 348.869 -83.2866) (xy 349.377 -83.2866)
				)
			)
		)
	)
)
